(kicad_pcb
	(version 20241229)
	(generator "pcbnew")
	(generator_version "9.0")
	(general
		(thickness 1.63)
		(legacy_teardrops no)
	)
	(paper "A4")
	(title_block
		(title "CM4 Baseboard")
		(date "2026-01-05")
		(rev "1.1.1")
		(company "Antmicro Ltd")
		(comment 1 "www.antmicro.com")
		(comment 9 "footprints 206-210 of 506")
	)
	(layers
		(0 "F.Cu" signal)
		(4 "In1.Cu" power)
		(6 "In2.Cu" power)
		(8 "In3.Cu" signal)
		(10 "In4.Cu" signal)
		(2 "B.Cu" signal)
		(9 "F.Adhes" user "F.Adhesive")
		(11 "B.Adhes" user "B.Adhesive")
		(13 "F.Paste" user)
		(15 "B.Paste" user)
		(5 "F.SilkS" user "F.Silkscreen")
		(7 "B.SilkS" user "B.Silkscreen")
		(1 "F.Mask" user)
		(3 "B.Mask" user)
		(17 "Dwgs.User" user "User.Drawings")
		(19 "Cmts.User" user "User.Comments")
		(21 "Eco1.User" user "User.Eco1")
		(23 "Eco2.User" user "User.Eco2")
		(25 "Edge.Cuts" user)
		(27 "Margin" user)
		(31 "F.CrtYd" user "F.Courtyard")
		(29 "B.CrtYd" user "B.Courtyard")
		(35 "F.Fab" user)
		(33 "B.Fab" user)
	)
	(footprint "antmicro-footprints:R_0402_1005Metric"
		(layer "F.Cu")
		(at 130.717962 157.7915 90)
		(descr "Resistor SMD 0402")
		(tags "resistor SMD 0402")
		(property "Reference" "R603"
			(at -0.9785 -0.817962 90)
			(layer "F.SilkS")
			(effects
				(font
					(size 0.7 0.7)
					(thickness 0.15)
				)
				(justify left bottom)
			)
		)
		(property "Value" "R_10k_0402"
			(at -1.011843 1.772047 90)
			(layer "F.Fab")
			(effects
				(font
					(size 0.7 0.7)
					(thickness 0.15)
				)
				(justify left bottom)
			)
		)
		(property "Datasheet" "https://www.bourns.com/docs/product-datasheets/cr.pdf"
			(at 0 0 90)
			(layer "F.Fab")
			(hide yes)
			(effects
				(font
					(size 1.27 1.27)
					(thickness 0.15)
				)
			)
		)
		(property "Manufacturer" "Bourns"
			(at 0 0 90)
			(unlocked yes)
			(layer "F.Fab")
			(hide yes)
			(effects
				(font
					(size 1 1)
					(thickness 0.15)
				)
			)
		)
		(property "MPN" "CR0402-FX-1002GLF"
			(at 0 0 90)
			(unlocked yes)
			(layer "F.Fab")
			(hide yes)
			(effects
				(font
					(size 1 1)
					(thickness 0.15)
				)
			)
		)
		(property "Val" "10k"
			(at 0 0 90)
			(unlocked yes)
			(layer "F.Fab")
			(hide yes)
			(effects
				(font
					(size 1 1)
					(thickness 0.15)
				)
			)
		)
		(property "License" "Apache-2.0"
			(at 0 0 90)
			(unlocked yes)
			(layer "F.Fab")
			(hide yes)
			(effects
				(font
					(size 1 1)
					(thickness 0.15)
				)
			)
		)
		(property "Author" "Antmicro"
			(at 0 0 90)
			(unlocked yes)
			(layer "F.Fab")
			(hide yes)
			(effects
				(font
					(size 1 1)
					(thickness 0.15)
				)
			)
		)
		(property "Tolerance" "1%"
			(at 0 0 90)
			(unlocked yes)
			(layer "F.Fab")
			(hide yes)
			(effects
				(font
					(size 1 1)
					(thickness 0.15)
				)
			)
		)
		(sheetname "/CSI/")
		(sheetfile "csi.kicad_sch")
		(attr smd)
		(fp_rect
			(start -0.925 -0.47)
			(end 0.925 0.47)
			(stroke
				(width 0.05)
				(type default)
			)
			(fill no)
			(layer "F.CrtYd")
		)
		(fp_rect
			(start -0.5 -0.25)
			(end 0.5 0.25)
			(stroke
				(width 0.15)
				(type solid)
			)
			(fill no)
			(layer "F.Fab")
		)
		(fp_text user "License: Apache-2.0"
			(at -0.95 5.169 90)
			(layer "F.Fab")
			(effects
				(font
					(size 0.7 0.7)
					(thickness 0.15)
				)
				(justify left bottom)
			)
		)
		(fp_text user "Author: Antmicro"
			(at -0.95 4.169 90)
			(layer "F.Fab")
			(effects
				(font
					(size 0.7 0.7)
					(thickness 0.15)
				)
				(justify left bottom)
			)
		)
		(fp_text user "${REFERENCE}"
			(at -0.95 3.168 90)
			(layer "F.Fab")
			(effects
				(font
					(size 0.7 0.7)
					(thickness 0.15)
				)
				(justify left bottom)
			)
		)
		(pad "1" smd roundrect
			(at -0.48 0 90)
			(size 0.59 0.64)
			(layers "F.Cu" "F.Mask" "F.Paste")
			(roundrect_rratio 0.25)
			(net 9 "+3V3")
			(pintype "passive")
		)
		(pad "2" smd roundrect
			(at 0.48 0 90)
			(size 0.59 0.64)
			(layers "F.Cu" "F.Mask" "F.Paste")
			(roundrect_rratio 0.25)
			(net 371 "Net-(U602-FLG)")
			(pintype "passive")
		)
	)
	(footprint "antmicro-footprints:Conv_Murata_ULS-60W"
		(layer "F.Cu")
		(at 59.937962 139.8265 -90)
		(property "Reference" "U403"
			(at -1.7265 -4.262038 270)
			(layer "F.SilkS")
			(effects
				(font
					(size 0.7 0.7)
					(thickness 0.15)
				)
				(justify left bottom)
			)
		)
		(property "Value" "ULS-12_5-D48N-C"
			(at -2.8 20.1 270)
			(layer "F.Fab")
			(effects
				(font
					(size 0.7 0.7)
					(thickness 0.15)
				)
				(justify left bottom)
			)
		)
		(property "Datasheet" "https://www.murata.com/products/productdata/8807040286750/uls.pdf?1649388617000"
			(at 0 0 270)
			(layer "F.Fab")
			(hide yes)
			(effects
				(font
					(size 1.27 1.27)
					(thickness 0.15)
				)
			)
		)
		(property "Description" "Isolated Through Hole DC/DC Converter, ITE, 2:1, 60 W, 1 Output, 12 V, 5 A"
			(at 0 0 270)
			(layer "F.Fab")
			(hide yes)
			(effects
				(font
					(size 1.27 1.27)
					(thickness 0.15)
				)
			)
		)
		(property "Manufacturer" "Murata"
			(at 0 0 270)
			(unlocked yes)
			(layer "F.Fab")
			(hide yes)
			(effects
				(font
					(size 1 1)
					(thickness 0.15)
				)
			)
		)
		(property "MPN" "ULS-12/5-D48N-C"
			(at 0 0 270)
			(unlocked yes)
			(layer "F.Fab")
			(hide yes)
			(effects
				(font
					(size 1 1)
					(thickness 0.15)
				)
			)
		)
		(property "Author" "Antmicro"
			(at 0 0 270)
			(unlocked yes)
			(layer "F.Fab")
			(hide yes)
			(effects
				(font
					(size 1 1)
					(thickness 0.15)
				)
			)
		)
		(property "License" "Apache-2.0"
			(at 0 0 270)
			(unlocked yes)
			(layer "F.Fab")
			(hide yes)
			(effects
				(font
					(size 1 1)
					(thickness 0.15)
				)
			)
		)
		(property "Alternatives 50W" " VCB4812SBO-50WR3, V36SE12004NRFA, PKU5513ESI, KHHD004A2B41Z"
			(at 0 0 270)
			(unlocked yes)
			(layer "F.Fab")
			(hide yes)
			(effects
				(font
					(size 1 1)
					(thickness 0.15)
				)
			)
		)
		(property "Alternatives 75W" " VCB4812SBO-75WR3"
			(at 0 0 270)
			(unlocked yes)
			(layer "F.Fab")
			(hide yes)
			(effects
				(font
					(size 1 1)
					(thickness 0.15)
				)
			)
		)
		(property "Alternatives 100W" "PKU4913DPIHS, VCB4812SBO-100WFR3"
			(at 0 0 270)
			(unlocked yes)
			(layer "F.Fab")
			(hide yes)
			(effects
				(font
					(size 1 1)
					(thickness 0.15)
				)
			)
		)
		(property "Alternatives 120W" "PQC50-48-S12-O"
			(at 0 0 270)
			(unlocked yes)
			(layer "F.Fab")
			(hide yes)
			(effects
				(font
					(size 1 1)
					(thickness 0.15)
				)
			)
		)
		(sheetname "/Ethernet/")
		(sheetfile "ethernet.kicad_sch")
		(attr through_hole)
		(fp_line
			(start -2.535 19.053)
			(end -2.535 -2.537)
			(stroke
				(width 0.15)
				(type solid)
			)
			(layer "F.SilkS")
		)
		(fp_line
			(start 30.485 19.053)
			(end -2.535 19.053)
			(stroke
				(width 0.15)
				(type solid)
			)
			(layer "F.SilkS")
		)
		(fp_line
			(start 30.485 19.053)
			(end 30.485 -3.807)
			(stroke
				(width 0.15)
				(type solid)
			)
			(layer "F.SilkS")
		)
		(fp_line
			(start -2.535 -2.537)
			(end -1.265 -3.807)
			(stroke
				(width 0.15)
				(type solid)
			)
			(layer "F.SilkS")
		)
		(fp_line
			(start 30.485 -3.807)
			(end -1.265 -3.807)
			(stroke
				(width 0.15)
				(type solid)
			)
			(layer "F.SilkS")
		)
		(fp_circle
			(center -1.9 0)
			(end -1.85 0)
			(stroke
				(width 0.15)
				(type solid)
			)
			(fill yes)
			(layer "F.SilkS")
		)
		(fp_rect
			(start -3.54 -4.81)
			(end 31.48 20.05)
			(stroke
				(width 0.05)
				(type solid)
			)
			(fill no)
			(layer "F.CrtYd")
		)
		(fp_line
			(start -2.535 19.053)
			(end -2.535 -2.537)
			(stroke
				(width 0.15)
				(type solid)
			)
			(layer "F.Fab")
		)
		(fp_line
			(start 30.485 19.053)
			(end -2.535 19.053)
			(stroke
				(width 0.15)
				(type solid)
			)
			(layer "F.Fab")
		)
		(fp_line
			(start 30.485 19.053)
			(end 30.485 -3.807)
			(stroke
				(width 0.15)
				(type solid)
			)
			(layer "F.Fab")
		)
		(fp_line
			(start -2.535 -2.537)
			(end -1.265 -3.807)
			(stroke
				(width 0.15)
				(type solid)
			)
			(layer "F.Fab")
		)
		(fp_line
			(start 30.485 -3.807)
			(end -1.265 -3.807)
			(stroke
				(width 0.15)
				(type solid)
			)
			(layer "F.Fab")
		)
		(fp_text user "License: Apache-2.0"
			(at -3.54 24.45 270)
			(layer "F.Fab")
			(effects
				(font
					(size 0.7 0.7)
					(thickness 0.15)
				)
				(justify left bottom)
			)
		)
		(fp_text user "${REFERENCE}"
			(at -3.54 23.25 270)
			(layer "F.Fab")
			(effects
				(font
					(size 0.7 0.7)
					(thickness 0.15)
				)
				(justify left bottom)
			)
		)
		(fp_text user "Author: Antmicro"
			(at -3.54 22.05 270)
			(layer "F.Fab")
			(effects
				(font
					(size 0.7 0.7)
					(thickness 0.15)
				)
				(justify left bottom)
			)
		)
		(pad "1" thru_hole rect
			(at 0 0 270)
			(size 2.54 2.54)
			(drill 1.4)
			(layers "*.Cu" "*.Mask")
			(remove_unused_layers no)
			(net 33 "/Ethernet/VDD")
			(pinfunction "VIN+")
			(pintype "power_in")
		)
		(pad "2" thru_hole circle
			(at 0 7.62 270)
			(size 2.54 2.54)
			(drill 1.4)
			(layers "*.Cu" "*.Mask")
			(remove_unused_layers no)
			(net 126 "/Ethernet/ULS-12_CTRL")
			(pinfunction "CTRL")
			(pintype "input")
		)
		(pad "3" thru_hole circle
			(at 0 15.24 270)
			(size 2.54 2.54)
			(drill 1.4)
			(layers "*.Cu" "*.Mask")
			(remove_unused_layers no)
			(net 1 "GNDD")
			(pinfunction "VIN-")
			(pintype "power_in")
		)
		(pad "4" thru_hole circle
			(at 27.94 15.24 270)
			(size 2.54 2.54)
			(drill 1.956)
			(layers "*.Cu" "*.Mask")
			(remove_unused_layers no)
			(net 3 "GND")
			(pinfunction "VOUT-")
			(pintype "power_out")
		)
		(pad "5" thru_hole circle
			(at 27.94 11.43 270)
			(size 2.54 2.54)
			(drill 1.4)
			(layers "*.Cu" "*.Mask")
			(remove_unused_layers no)
			(net 3 "GND")
			(pinfunction "SENSE-")
			(pintype "passive")
		)
		(pad "6" thru_hole circle
			(at 27.94 7.62 270)
			(size 2.54 2.54)
			(drill 1.4)
			(layers "*.Cu" "*.Mask")
			(remove_unused_layers no)
			(net 368 "Net-(U403-TRIM)")
			(pinfunction "TRIM")
			(pintype "input")
		)
		(pad "7" thru_hole circle
			(at 27.94 3.81 270)
			(size 2.54 2.54)
			(drill 1.4)
			(layers "*.Cu" "*.Mask")
			(remove_unused_layers no)
			(net 47 "/Ethernet/POE_12V")
			(pinfunction "SENSE+")
			(pintype "passive")
		)
		(pad "8" thru_hole circle
			(at 27.94 0 270)
			(size 2.54 2.54)
			(drill 1.956)
			(layers "*.Cu" "*.Mask")
			(remove_unused_layers no)
			(net 47 "/Ethernet/POE_12V")
			(pinfunction "VOUT+")
			(pintype "power_out")
		)
	)
	(footprint "antmicro-footprints:TP_SMD_0.75mm"
		(layer "F.Cu")
		(at 93.8 130.85)
		(property "Reference" "TP904"
			(at 3.03 2.64 0)
			(layer "F.SilkS")
			(effects
				(font
					(size 0.7 0.7)
					(thickness 0.15)
				)
				(justify left bottom)
			)
		)
		(property "Value" "TP_0.75mm_SMD"
			(at 0 1.2 0)
			(layer "F.Fab")
			(effects
				(font
					(size 0.7 0.7)
					(thickness 0.15)
				)
				(justify left bottom)
			)
		)
		(property "MPN" ""
			(at 0 0 0)
			(unlocked yes)
			(layer "F.Fab")
			(hide yes)
			(effects
				(font
					(size 1 1)
					(thickness 0.15)
				)
			)
		)
		(property "Manufacturer" ""
			(at 0 0 0)
			(unlocked yes)
			(layer "F.Fab")
			(hide yes)
			(effects
				(font
					(size 1 1)
					(thickness 0.15)
				)
			)
		)
		(property "Author" "Antmicro"
			(at 0 0 0)
			(unlocked yes)
			(layer "F.Fab")
			(hide yes)
			(effects
				(font
					(size 1 1)
					(thickness 0.15)
				)
			)
		)
		(property "License" "Apache-2.0"
			(at 0 0 0)
			(unlocked yes)
			(layer "F.Fab")
			(hide yes)
			(effects
				(font
					(size 1 1)
					(thickness 0.15)
				)
			)
		)
		(sheetname "/USB/")
		(sheetfile "usb.kicad_sch")
		(attr exclude_from_pos_files exclude_from_bom)
		(fp_circle
			(center 0 0)
			(end 0.475 0)
			(stroke
				(width 0.05)
				(type default)
			)
			(fill no)
			(layer "F.CrtYd")
		)
		(fp_text user "Author: Antmicro"
			(at -0.4 3.901 0)
			(layer "F.Fab")
			(effects
				(font
					(size 0.7 0.7)
					(thickness 0.15)
				)
				(justify left bottom)
			)
		)
		(fp_text user "${REFERENCE}"
			(at -0.4 2.7 0)
			(layer "F.Fab")
			(effects
				(font
					(size 0.7 0.7)
					(thickness 0.15)
				)
				(justify left bottom)
			)
		)
		(fp_text user "License: Apache-2.0"
			(at -0.4 5.101 0)
			(layer "F.Fab")
			(effects
				(font
					(size 0.7 0.7)
					(thickness 0.15)
				)
				(justify left bottom)
			)
		)
		(pad "1" smd circle
			(at 0 0)
			(size 0.75 0.75)
			(layers "F.Cu" "F.Mask")
			(net 448 "Net-(U905-GPIO0)")
			(pinfunction "1")
			(pintype "passive")
		)
	)
	(footprint "antmicro-footprints:R_0402_1005Metric"
		(layer "F.Cu")
		(at 76.7 170.0665 -90)
		(descr "Resistor SMD 0402")
		(tags "resistor SMD 0402")
		(property "Reference" "R240"
			(at -3.98 -11.56 90)
			(layer "F.SilkS")
			(effects
				(font
					(size 0.7 0.7)
					(thickness 0.15)
				)
				(justify right bottom)
			)
		)
		(property "Value" "R_0R_0402"
			(at -1.011843 1.772047 90)
			(layer "F.Fab")
			(effects
				(font
					(size 0.7 0.7)
					(thickness 0.15)
				)
				(justify right bottom)
			)
		)
		(property "Datasheet" "https://industrial.panasonic.com/cdbs/www-data/pdf/RDA0000/AOA0000C301.pdf"
			(at 0 0 90)
			(layer "F.Fab")
			(hide yes)
			(effects
				(font
					(size 1.27 1.27)
					(thickness 0.15)
				)
			)
		)
		(property "Manufacturer" "Panasonic"
			(at 0 0 270)
			(unlocked yes)
			(layer "F.Fab")
			(hide yes)
			(effects
				(font
					(size 1 1)
					(thickness 0.15)
				)
			)
		)
		(property "MPN" "ERJ2GE0R00X"
			(at 0 0 270)
			(unlocked yes)
			(layer "F.Fab")
			(hide yes)
			(effects
				(font
					(size 1 1)
					(thickness 0.15)
				)
			)
		)
		(property "Val" "0R"
			(at 0 0 270)
			(unlocked yes)
			(layer "F.Fab")
			(hide yes)
			(effects
				(font
					(size 1 1)
					(thickness 0.15)
				)
			)
		)
		(property "License" "Apache-2.0"
			(at 0 0 270)
			(unlocked yes)
			(layer "F.Fab")
			(hide yes)
			(effects
				(font
					(size 1 1)
					(thickness 0.15)
				)
			)
		)
		(property "Author" "Antmicro"
			(at 0 0 270)
			(unlocked yes)
			(layer "F.Fab")
			(hide yes)
			(effects
				(font
					(size 1 1)
					(thickness 0.15)
				)
			)
		)
		(property "Tolerance" "~"
			(at 0 0 270)
			(unlocked yes)
			(layer "F.Fab")
			(hide yes)
			(effects
				(font
					(size 1 1)
					(thickness 0.15)
				)
			)
		)
		(property "Current" "1A"
			(at 0 0 270)
			(unlocked yes)
			(layer "F.Fab")
			(hide yes)
			(effects
				(font
					(size 1 1)
					(thickness 0.15)
				)
			)
		)
		(sheetname "/Compute module/")
		(sheetfile "compute-module.kicad_sch")
		(attr smd)
		(fp_rect
			(start -0.925 -0.47)
			(end 0.925 0.47)
			(stroke
				(width 0.05)
				(type default)
			)
			(fill no)
			(layer "F.CrtYd")
		)
		(fp_rect
			(start -0.5 -0.25)
			(end 0.5 0.25)
			(stroke
				(width 0.15)
				(type solid)
			)
			(fill no)
			(layer "F.Fab")
		)
		(fp_text user "Author: Antmicro"
			(at -0.95 4.169 90)
			(layer "F.Fab")
			(effects
				(font
					(size 0.7 0.7)
					(thickness 0.15)
				)
				(justify right top)
			)
		)
		(fp_text user "License: Apache-2.0"
			(at -0.95 5.169 90)
			(layer "F.Fab")
			(effects
				(font
					(size 0.7 0.7)
					(thickness 0.15)
				)
				(justify right top)
			)
		)
		(fp_text user "${REFERENCE}"
			(at -0.95 3.168 90)
			(layer "F.Fab")
			(effects
				(font
					(size 0.7 0.7)
					(thickness 0.15)
				)
				(justify right top)
			)
		)
		(pad "1" smd roundrect
			(at -0.48 0 270)
			(size 0.59 0.64)
			(layers "F.Cu" "F.Mask" "F.Paste")
			(roundrect_rratio 0.25)
			(net 276 "Net-(U204-GPA3)")
			(pintype "passive")
		)
		(pad "2" smd roundrect
			(at 0.48 0 270)
			(size 0.59 0.64)
			(layers "F.Cu" "F.Mask" "F.Paste")
			(roundrect_rratio 0.25)
			(net 328 "/Compute module/NFC.WKUP_REQ")
			(pintype "passive")
		)
	)
	(footprint "antmicro-footprints:R_0402_1005Metric"
		(layer "F.Cu")
		(at 102.542962 154.2915 90)
		(descr "Resistor SMD 0402")
		(tags "resistor SMD 0402")
		(property "Reference" "R203"
			(at -1.122484 -0.772697 90)
			(layer "F.SilkS")
			(effects
				(font
					(size 0.7 0.7)
					(thickness 0.15)
				)
				(justify left bottom)
			)
		)
		(property "Value" "R_100k_0402"
			(at -1.011843 1.772047 90)
			(layer "F.Fab")
			(effects
				(font
					(size 0.7 0.7)
					(thickness 0.15)
				)
				(justify left bottom)
			)
		)
		(property "Datasheet" "https://www.bourns.com/docs/product-datasheets/cr.pdf"
			(at 0 0 90)
			(layer "F.Fab")
			(hide yes)
			(effects
				(font
					(size 1.27 1.27)
					(thickness 0.15)
				)
			)
		)
		(property "MPN" "CR0402-FX-1003GLF"
			(at 0 0 90)
			(unlocked yes)
			(layer "F.Fab")
			(hide yes)
			(effects
				(font
					(size 1 1)
					(thickness 0.15)
				)
			)
		)
		(property "Manufacturer" "Bourns"
			(at 0 0 90)
			(unlocked yes)
			(layer "F.Fab")
			(hide yes)
			(effects
				(font
					(size 1 1)
					(thickness 0.15)
				)
			)
		)
		(property "License" "Apache-2.0"
			(at 0 0 90)
			(unlocked yes)
			(layer "F.Fab")
			(hide yes)
			(effects
				(font
					(size 1 1)
					(thickness 0.15)
				)
			)
		)
		(property "Author" "Antmicro"
			(at 0 0 90)
			(unlocked yes)
			(layer "F.Fab")
			(hide yes)
			(effects
				(font
					(size 1 1)
					(thickness 0.15)
				)
			)
		)
		(property "Val" "100k"
			(at 0 0 90)
			(unlocked yes)
			(layer "F.Fab")
			(hide yes)
			(effects
				(font
					(size 1 1)
					(thickness 0.15)
				)
			)
		)
		(property "Tolerance" "1%"
			(at 0 0 90)
			(unlocked yes)
			(layer "F.Fab")
			(hide yes)
			(effects
				(font
					(size 1 1)
					(thickness 0.15)
				)
			)
		)
		(sheetname "/Compute module/")
		(sheetfile "compute-module.kicad_sch")
		(attr smd)
		(fp_rect
			(start -0.925 -0.47)
			(end 0.925 0.47)
			(stroke
				(width 0.05)
				(type default)
			)
			(fill no)
			(layer "F.CrtYd")
		)
		(fp_rect
			(start -0.5 -0.25)
			(end 0.5 0.25)
			(stroke
				(width 0.15)
				(type solid)
			)
			(fill no)
			(layer "F.Fab")
		)
		(fp_text user "${REFERENCE}"
			(at -0.95 3.168 90)
			(layer "F.Fab")
			(effects
				(font
					(size 0.7 0.7)
					(thickness 0.15)
				)
				(justify left bottom)
			)
		)
		(fp_text user "License: Apache-2.0"
			(at -0.95 5.169 90)
			(layer "F.Fab")
			(effects
				(font
					(size 0.7 0.7)
					(thickness 0.15)
				)
				(justify left bottom)
			)
		)
		(fp_text user "Author: Antmicro"
			(at -0.95 4.169 90)
			(layer "F.Fab")
			(effects
				(font
					(size 0.7 0.7)
					(thickness 0.15)
				)
				(justify left bottom)
			)
		)
		(pad "1" smd roundrect
			(at -0.48 0 90)
			(size 0.59 0.64)
			(layers "F.Cu" "F.Mask" "F.Paste")
			(roundrect_rratio 0.25)
			(net 10 "+5V")
			(pintype "passive")
		)
		(pad "2" smd roundrect
			(at 0.48 0 90)
			(size 0.59 0.64)
			(layers "F.Cu" "F.Mask" "F.Paste")
			(roundrect_rratio 0.25)
			(net 327 "Net-(Q201-D)")
			(pintype "passive")
		)
	)
)
